# SCM (Grand Teton) — schematic netlist excerpt (pin names and nets, part order shuffled) for the footprints in the layout excerpt that follows; sources: Cadence DE-HDL packaged netlist, KiCad conversion of 12092022_DA0F0TMDCD0_F0T_Management_Board_D_brd_V3_OCP.brd

C81  Q_CAP  0.1UF 25V 10% X7R  pkg 0402  page 17 : A = P1V8_STBY_RC_VCC18A ; B = GND
R629  Q_RES  0 5% CHIP  pkg 0402LF  page 31 : A = BMC_CPLD_GPIO_2 ; B = FM_DBG_SW_N

(kicad_pcb
	(version 20260206)
	(generator "pcbnew")
	(generator_version "10.0")
	(general
		(thickness 1.6)
		(legacy_teardrops no)
	)
	(paper "A4")
	(title_block
		(title "12092022_DA0F0TMDCD0_F0T_Management_Board_D_brd_V3_OCP.brd")
		(comment 1 "Grand Teton / footprints 851-852 of 1440")
	)
	(layers
		(0 "F.Cu" signal "TOP")
		(4 "In1.Cu" signal "GND")
		(6 "In2.Cu" signal "IN1")
		(8 "In3.Cu" signal "GND1")
		(10 "In4.Cu" signal "IN2")
		(12 "In5.Cu" signal "VCC")
		(14 "In6.Cu" signal "VCC1")
		(16 "In7.Cu" signal "IN3")
		(18 "In8.Cu" signal "GND2")
		(20 "In9.Cu" signal "IN4")
		(22 "In10.Cu" signal "GND3")
		(2 "B.Cu" signal "BOTTOM")
		(9 "F.Adhes" user "F.Adhesive")
		(11 "B.Adhes" user "B.Adhesive")
		(13 "F.Paste" user "Package Geometry/Pastemask Top")
		(15 "B.Paste" user "Package Geometry/Pastemask Bottom")
		(5 "F.SilkS" user "Ref Des/Silkscreen Top")
		(7 "B.SilkS" user "Ref Des/Silkscreen Bottom")
		(1 "F.Mask" user "Board Geometry/Soldermask Top")
		(3 "B.Mask" user "Board Geometry/Soldermask Bottom")
		(17 "Dwgs.User" user "User.Drawings")
		(19 "Cmts.User" user "User.Comments")
		(21 "Eco1.User" user "User.Eco1")
		(23 "Eco2.User" user "User.Eco2")
		(25 "Edge.Cuts" user "Board Geometry/Outline")
		(27 "Margin" user)
		(31 "F.CrtYd" user "Package Geometry/Place Bound Top")
		(29 "B.CrtYd" user "Package Geometry/Place Bound Bottom")
		(35 "F.Fab" user "Ref Des/Assembly Top")
		(33 "B.Fab" user "Ref Des/Assembly Bottom")
	)
	(footprint ""
		(layer "B.Cu")
		(at 64.262 -18.669 90)
		(property "Reference" "R629"
			(at 0 0 90)
			(layer "B.SilkS")
			(hide yes)
			(effects
				(font
					(size 1.27 1.27)
				)
				(justify mirror)
			)
		)
		(property "Value" ""
			(at 0 0 90)
			(layer "B.Fab")
			(effects
				(font
					(size 1.27 1.27)
				)
				(justify mirror)
			)
		)
		(duplicate_pad_numbers_are_jumpers no)
		(fp_line
			(start 0.7874 -0.4064)
			(end -0.7874 -0.4064)
			(stroke
				(width 0.1524)
				(type default)
			)
			(layer "B.SilkS")
		)
		(fp_line
			(start -0.7874 -0.4064)
			(end -0.7874 0.4064)
			(stroke
				(width 0.1524)
				(type default)
			)
			(layer "B.SilkS")
		)
		(fp_line
			(start 0.7874 0.4064)
			(end 0.7874 -0.4064)
			(stroke
				(width 0.1524)
				(type default)
			)
			(layer "B.SilkS")
		)
		(fp_line
			(start -0.7874 0.4064)
			(end 0.7874 0.4064)
			(stroke
				(width 0.1524)
				(type default)
			)
			(layer "B.SilkS")
		)
		(fp_line
			(start 0.67945 -0.305054)
			(end 0.12065 -0.305054)
			(stroke
				(width 0.1)
				(type default)
			)
			(layer "B.Fab")
		)
		(fp_line
			(start 0.12065 -0.305054)
			(end 0.12065 -0.2794)
			(stroke
				(width 0.1)
				(type default)
			)
			(layer "B.Fab")
		)
		(fp_line
			(start -0.12065 -0.3048)
			(end -0.67945 -0.3048)
			(stroke
				(width 0.1)
				(type default)
			)
			(layer "B.Fab")
		)
		(fp_line
			(start -0.67945 -0.3048)
			(end -0.67945 0.3048)
			(stroke
				(width 0.1)
				(type default)
			)
			(layer "B.Fab")
		)
		(fp_line
			(start 0.12065 -0.2794)
			(end -0.12065 -0.2794)
			(stroke
				(width 0.1)
				(type default)
			)
			(layer "B.Fab")
		)
		(fp_line
			(start -0.12065 -0.2794)
			(end -0.12065 -0.3048)
			(stroke
				(width 0.1)
				(type default)
			)
			(layer "B.Fab")
		)
		(fp_line
			(start 0.12065 0.2794)
			(end 0.12065 0.3048)
			(stroke
				(width 0.1)
				(type default)
			)
			(layer "B.Fab")
		)
		(fp_line
			(start -0.120396 0.2794)
			(end 0.12065 0.2794)
			(stroke
				(width 0.1)
				(type default)
			)
			(layer "B.Fab")
		)
		(fp_line
			(start 0.67945 0.3048)
			(end 0.67945 -0.305054)
			(stroke
				(width 0.1)
				(type default)
			)
			(layer "B.Fab")
		)
		(fp_line
			(start 0.12065 0.3048)
			(end 0.67945 0.3048)
			(stroke
				(width 0.1)
				(type default)
			)
			(layer "B.Fab")
		)
		(fp_line
			(start -0.120396 0.3048)
			(end -0.120396 0.2794)
			(stroke
				(width 0.1)
				(type default)
			)
			(layer "B.Fab")
		)
		(fp_line
			(start -0.67945 0.3048)
			(end -0.120396 0.3048)
			(stroke
				(width 0.1)
				(type default)
			)
			(layer "B.Fab")
		)
		(pad "1" smd circle
			(at 0.40005 0 270)
			(size 0 0)
			(layers "B.Cu" "B.Mask" "B.Paste")
			(net "BMC_CPLD_GPIO_2")
		)
		(pad "2" smd circle
			(at -0.40005 0 270)
			(size 0 0)
			(layers "B.Cu" "B.Mask" "B.Paste")
			(net "FM_DBG_SW_N")
		)
	)
	(footprint ""
		(layer "B.Cu")
		(at 56.983376 -53.376322)
		(property "Reference" "C81"
			(at 0 0 0)
			(layer "B.SilkS")
			(hide yes)
			(effects
				(font
					(size 1.27 1.27)
				)
				(justify mirror)
			)
		)
		(property "Value" ""
			(at 0 0 0)
			(layer "B.Fab")
			(effects
				(font
					(size 1.27 1.27)
				)
				(justify mirror)
			)
		)
		(duplicate_pad_numbers_are_jumpers no)
		(fp_line
			(start -0.7874 -0.4064)
			(end -0.7874 0.4064)
			(stroke
				(width 0.1524)
				(type default)
			)
			(layer "B.SilkS")
		)
		(fp_line
			(start -0.7874 0.4064)
			(end 0.7874 0.4064)
			(stroke
				(width 0.1524)
				(type default)
			)
			(layer "B.SilkS")
		)
		(fp_line
			(start 0.7874 -0.4064)
			(end -0.7874 -0.4064)
			(stroke
				(width 0.1524)
				(type default)
			)
			(layer "B.SilkS")
		)
		(fp_line
			(start 0.7874 0.4064)
			(end 0.7874 -0.4064)
			(stroke
				(width 0.1524)
				(type default)
			)
			(layer "B.SilkS")
		)
		(fp_line
			(start -0.67945 -0.3048)
			(end -0.67945 0.3048)
			(stroke
				(width 0.1)
				(type default)
			)
			(layer "B.Fab")
		)
		(fp_line
			(start -0.67945 0.3048)
			(end -0.120396 0.3048)
			(stroke
				(width 0.1)
				(type default)
			)
			(layer "B.Fab")
		)
		(fp_line
			(start -0.12065 -0.3048)
			(end -0.67945 -0.3048)
			(stroke
				(width 0.1)
				(type default)
			)
			(layer "B.Fab")
		)
		(fp_line
			(start -0.12065 -0.2794)
			(end -0.12065 -0.3048)
			(stroke
				(width 0.1)
				(type default)
			)
			(layer "B.Fab")
		)
		(fp_line
			(start -0.120396 0.2794)
			(end 0.12065 0.2794)
			(stroke
				(width 0.1)
				(type default)
			)
			(layer "B.Fab")
		)
		(fp_line
			(start -0.120396 0.3048)
			(end -0.120396 0.2794)
			(stroke
				(width 0.1)
				(type default)
			)
			(layer "B.Fab")
		)
		(fp_line
			(start 0.12065 -0.305054)
			(end 0.12065 -0.2794)
			(stroke
				(width 0.1)
				(type default)
			)
			(layer "B.Fab")
		)
		(fp_line
			(start 0.12065 -0.2794)
			(end -0.12065 -0.2794)
			(stroke
				(width 0.1)
				(type default)
			)
			(layer "B.Fab")
		)
		(fp_line
			(start 0.12065 0.2794)
			(end 0.12065 0.3048)
			(stroke
				(width 0.1)
				(type default)
			)
			(layer "B.Fab")
		)
		(fp_line
			(start 0.12065 0.3048)
			(end 0.67945 0.3048)
			(stroke
				(width 0.1)
				(type default)
			)
			(layer "B.Fab")
		)
		(fp_line
			(start 0.67945 -0.305054)
			(end 0.12065 -0.305054)
			(stroke
				(width 0.1)
				(type default)
			)
			(layer "B.Fab")
		)
		(fp_line
			(start 0.67945 0.3048)
			(end 0.67945 -0.305054)
			(stroke
				(width 0.1)
				(type default)
			)
			(layer "B.Fab")
		)
		(pad "1" smd circle
			(at 0.40005 0 180)
			(size 0 0)
			(layers "B.Cu" "B.Mask" "B.Paste")
			(net "P1V8_STBY_RC_VCC18A")
		)
		(pad "2" smd circle
			(at -0.40005 0 180)
			(size 0 0)
			(layers "B.Cu" "B.Mask" "B.Paste")
			(net "GND")
		)
	)
)
